(kicad_pcb
	(version 20241229)
	(generator "pcbnew")
	(generator_version "9.0")
	(general
		(thickness 1.6)
		(legacy_teardrops no)
	)
	(paper "A4")
	(title_block
		(title "environment-sensor")
		(comment 1 "footprints 8-11 of 109")
	)
	(layers
		(0 "F.Cu" signal)
		(4 "In1.Cu" signal)
		(6 "In2.Cu" signal)
		(2 "B.Cu" signal)
		(9 "F.Adhes" user "F.Adhesive")
		(11 "B.Adhes" user "B.Adhesive")
		(13 "F.Paste" user)
		(15 "B.Paste" user)
		(5 "F.SilkS" user "F.Silkscreen")
		(7 "B.SilkS" user "B.Silkscreen")
		(1 "F.Mask" user)
		(3 "B.Mask" user)
		(17 "Dwgs.User" user "User.Drawings")
		(19 "Cmts.User" user "User.Comments")
		(21 "Eco1.User" user "User.Eco1")
		(23 "Eco2.User" user "User.Eco2")
		(25 "Edge.Cuts" user)
		(27 "Margin" user)
		(31 "F.CrtYd" user "F.Courtyard")
		(29 "B.CrtYd" user "B.Courtyard")
		(35 "F.Fab" user)
		(33 "B.Fab" user)
	)
	(footprint "antmicro-footprints:Resonator_SMD_ECS_ECX-31B_3.2x1.5x0.9mm"
		(layer "F.Cu")
		(at 180.65 131.05 -90)
		(property "Reference" "Y1"
			(at -0.5 1.2 90)
			(layer "F.SilkS")
			(effects
				(font
					(size 0.7 0.7)
					(thickness 0.15)
				)
				(justify right bottom)
			)
		)
		(property "Value" "Resonator_32.768kHz_ECX-31B"
			(at 0 2.25 90)
			(layer "F.Fab")
			(effects
				(font
					(size 0.7 0.7)
					(thickness 0.15)
				)
				(justify right bottom)
			)
		)
		(property "Description" "Crystal, 32.768 kHz, SMT, 3.2mm x 1.5mm, 12.5 pF, 20 ppm, ECX-31B"
			(at 0 0 270)
			(layer "F.Fab")
			(hide yes)
			(effects
				(font
					(size 1.27 1.27)
					(thickness 0.15)
				)
			)
		)
		(property "Author" "Antmicro"
			(at 49.6 311.7 0)
			(layer "F.Fab")
			(hide yes)
			(effects
				(font
					(size 1 1)
					(thickness 0.15)
				)
			)
		)
		(property "License" "Apache-2.0"
			(at 49.6 311.7 0)
			(layer "F.Fab")
			(hide yes)
			(effects
				(font
					(size 1 1)
					(thickness 0.15)
				)
			)
		)
		(property "MPN" "ECS-.327-12.5-34B-TR"
			(at 49.6 311.7 0)
			(layer "F.Fab")
			(hide yes)
			(effects
				(font
					(size 1 1)
					(thickness 0.15)
				)
			)
		)
		(property "Manufacturer" "ECS Inc. International"
			(at 49.6 311.7 0)
			(layer "F.Fab")
			(hide yes)
			(effects
				(font
					(size 1 1)
					(thickness 0.15)
				)
			)
		)
		(property "Public" "False"
			(at 49.6 311.7 0)
			(layer "F.Fab")
			(hide yes)
			(effects
				(font
					(size 1 1)
					(thickness 0.15)
				)
			)
		)
		(property "Val" "32.768 kHz"
			(at 49.6 311.7 0)
			(layer "F.Fab")
			(hide yes)
			(effects
				(font
					(size 1 1)
					(thickness 0.15)
				)
			)
		)
		(sheetfile "environment-sensor.kicad_sch")
		(attr smd)
		(fp_rect
			(start -2.001 -1.25)
			(end 2 1.248)
			(stroke
				(width 0.05)
				(type solid)
			)
			(fill no)
			(layer "F.CrtYd")
		)
		(fp_line
			(start -1.601 0.748)
			(end 1.6 0.748)
			(stroke
				(width 0.15)
				(type solid)
			)
			(layer "F.Fab")
		)
		(fp_line
			(start -1.601 0.748)
			(end -1.6 -0.4)
			(stroke
				(width 0.15)
				(type solid)
			)
			(layer "F.Fab")
		)
		(fp_line
			(start 1.6 0.748)
			(end 1.6 -0.75)
			(stroke
				(width 0.15)
				(type solid)
			)
			(layer "F.Fab")
		)
		(fp_line
			(start -1.3 -0.75)
			(end -1.6 -0.4)
			(stroke
				(width 0.15)
				(type solid)
			)
			(layer "F.Fab")
		)
		(fp_line
			(start 1.6 -0.75)
			(end -1.3 -0.75)
			(stroke
				(width 0.15)
				(type solid)
			)
			(layer "F.Fab")
		)
		(pad "1" smd rect
			(at -1.25 0 270)
			(size 1.1 1.9)
			(layers "F.Cu" "F.Mask" "F.Paste")
			(net 86 "/OSC32_IN")
			(pintype "passive")
		)
		(pad "2" smd rect
			(at 1.25 0 270)
			(size 1.1 1.9)
			(layers "F.Cu" "F.Mask" "F.Paste")
			(net 87 "/OSC32_OUT")
			(pintype "passive")
		)
	)
	(footprint "antmicro-footprints:TP_SMD_1mm"
		(layer "F.Cu")
		(at 176.2 134.55)
		(property "Reference" "TP10"
			(at 0 -0.731898 0)
			(layer "F.SilkS")
			(hide yes)
			(effects
				(font
					(size 0.7 0.7)
					(thickness 0.15)
				)
				(justify left bottom)
			)
		)
		(property "Value" "TP_1mm_SMD"
			(at 0 1.4 0)
			(layer "F.Fab")
			(effects
				(font
					(size 0.7 0.7)
					(thickness 0.15)
				)
				(justify left bottom)
			)
		)
		(property "Description" "Test point 1mm SMD"
			(at 0 0 0)
			(layer "F.Fab")
			(hide yes)
			(effects
				(font
					(size 1.27 1.27)
					(thickness 0.15)
				)
			)
		)
		(property "Author" "Antmicro"
			(at 0 0 0)
			(layer "F.Fab")
			(hide yes)
			(effects
				(font
					(size 1 1)
					(thickness 0.15)
				)
			)
		)
		(property "License" "Apache-2.0"
			(at 0 0 0)
			(layer "F.Fab")
			(hide yes)
			(effects
				(font
					(size 1 1)
					(thickness 0.15)
				)
			)
		)
		(property "MPN" ""
			(at 0 0 0)
			(layer "F.Fab")
			(hide yes)
			(effects
				(font
					(size 1 1)
					(thickness 0.15)
				)
			)
		)
		(property "Manufacturer" ""
			(at 0 0 0)
			(layer "F.Fab")
			(hide yes)
			(effects
				(font
					(size 1 1)
					(thickness 0.15)
				)
			)
		)
		(property "Public" "False"
			(at 0 0 0)
			(layer "F.Fab")
			(hide yes)
			(effects
				(font
					(size 1 1)
					(thickness 0.15)
				)
			)
		)
		(sheetfile "environment-sensor.kicad_sch")
		(attr exclude_from_pos_files)
		(pad "1" smd circle
			(at 0 0)
			(size 1 1)
			(layers "F.Cu" "F.Mask")
			(net 1 "GND")
			(pinfunction "1")
			(pintype "passive")
		)
	)
	(footprint "antmicro-footprints:C_0402_1005Metric"
		(layer "F.Cu")
		(at 182.91 130.4 180)
		(descr "Capacitor SMD 0402")
		(tags "capacitor SMD 0402")
		(property "Reference" "C14"
			(at -3.04 -0.45 0)
			(layer "F.SilkS")
			(effects
				(font
					(size 0.7 0.7)
					(thickness 0.15)
				)
				(justify right bottom)
			)
		)
		(property "Value" "C_16p_0402"
			(at -1.022927 2.155213 0)
			(layer "F.Fab")
			(effects
				(font
					(size 0.7 0.7)
					(thickness 0.15)
				)
				(justify right bottom)
			)
		)
		(property "Description" "SMD Multilayer Ceramic Capacitor, General Purpose, 16 pF, 50 V, 0402 [1005 Metric], ± 5%, C0G / NP0"
			(at 0 0 180)
			(layer "F.Fab")
			(hide yes)
			(effects
				(font
					(size 1.27 1.27)
					(thickness 0.15)
				)
			)
		)
		(property "Author" "Antmicro"
			(at 365.82 260.8 0)
			(layer "F.Fab")
			(hide yes)
			(effects
				(font
					(size 1 1)
					(thickness 0.15)
				)
			)
		)
		(property "Dielectric" ""
			(at 365.82 260.8 0)
			(layer "F.Fab")
			(hide yes)
			(effects
				(font
					(size 1 1)
					(thickness 0.15)
				)
			)
		)
		(property "License" "Apache-2.0"
			(at 365.82 260.8 0)
			(layer "F.Fab")
			(hide yes)
			(effects
				(font
					(size 1 1)
					(thickness 0.15)
				)
			)
		)
		(property "MPN" "0402N160J500CT"
			(at 365.82 260.8 0)
			(layer "F.Fab")
			(hide yes)
			(effects
				(font
					(size 1 1)
					(thickness 0.15)
				)
			)
		)
		(property "Manufacturer" "Walsin"
			(at 365.82 260.8 0)
			(layer "F.Fab")
			(hide yes)
			(effects
				(font
					(size 1 1)
					(thickness 0.15)
				)
			)
		)
		(property "Public" "False"
			(at 365.82 260.8 0)
			(layer "F.Fab")
			(hide yes)
			(effects
				(font
					(size 1 1)
					(thickness 0.15)
				)
			)
		)
		(property "Val" "16p"
			(at 365.82 260.8 0)
			(layer "F.Fab")
			(hide yes)
			(effects
				(font
					(size 1 1)
					(thickness 0.15)
				)
			)
		)
		(property "Voltage" ""
			(at 365.82 260.8 0)
			(layer "F.Fab")
			(hide yes)
			(effects
				(font
					(size 1 1)
					(thickness 0.15)
				)
			)
		)
		(sheetfile "environment-sensor.kicad_sch")
		(attr smd)
		(fp_rect
			(start -0.925 -0.47)
			(end 0.925 0.47)
			(stroke
				(width 0.05)
				(type default)
			)
			(fill no)
			(layer "F.CrtYd")
		)
		(fp_line
			(start 0.504 0.248)
			(end -0.494 0.248)
			(stroke
				(width 0.15)
				(type solid)
			)
			(layer "F.Fab")
		)
		(fp_line
			(start 0.504 -0.25)
			(end 0.504 0.248)
			(stroke
				(width 0.15)
				(type solid)
			)
			(layer "F.Fab")
		)
		(fp_line
			(start -0.494 0.248)
			(end -0.494 -0.25)
			(stroke
				(width 0.15)
				(type solid)
			)
			(layer "F.Fab")
		)
		(fp_line
			(start -0.494 -0.25)
			(end 0.504 -0.25)
			(stroke
				(width 0.15)
				(type solid)
			)
			(layer "F.Fab")
		)
		(pad "1" smd roundrect
			(at -0.48 0 180)
			(size 0.59 0.64)
			(layers "F.Cu" "F.Mask" "F.Paste")
			(roundrect_rratio 0.25)
			(net 86 "/OSC32_IN")
			(pintype "passive")
		)
		(pad "2" smd roundrect
			(at 0.48 0 180)
			(size 0.59 0.64)
			(layers "F.Cu" "F.Mask" "F.Paste")
			(roundrect_rratio 0.25)
			(net 1 "GND")
			(pintype "passive")
		)
	)
	(footprint "antmicro-footprints:QFN-32-1EP_5x5mm"
		(layer "F.Cu")
		(at 175.9435 119.042 -90)
		(property "Reference" "U1"
			(at -2.342 -3.9065 0)
			(layer "F.SilkS")
			(effects
				(font
					(size 0.7 0.7)
					(thickness 0.15)
				)
				(justify right bottom)
			)
		)
		(property "Value" "FT232R_QFN"
			(at -4.939 3.91 90)
			(layer "F.Fab")
			(effects
				(font
					(size 0.7 0.7)
					(thickness 0.15)
				)
				(justify right bottom)
			)
		)
		(property "Description" "Interface Bridges, USB to UART, 1.8 V, 5.25 V, QFN, 32 Pins, -40 °C"
			(at 0 0 270)
			(layer "F.Fab")
			(hide yes)
			(effects
				(font
					(size 1.27 1.27)
					(thickness 0.15)
				)
			)
		)
		(property "Author" "Antmicro"
			(at 56.9015 294.9855 0)
			(layer "F.Fab")
			(hide yes)
			(effects
				(font
					(size 1 1)
					(thickness 0.15)
				)
			)
		)
		(property "License" "Apache-2.0"
			(at 56.9015 294.9855 0)
			(layer "F.Fab")
			(hide yes)
			(effects
				(font
					(size 1 1)
					(thickness 0.15)
				)
			)
		)
		(property "MPN" "FT232RQ-REEL"
			(at 56.9015 294.9855 0)
			(layer "F.Fab")
			(hide yes)
			(effects
				(font
					(size 1 1)
					(thickness 0.15)
				)
			)
		)
		(property "Manufacturer" "FTDI Chip"
			(at 56.9015 294.9855 0)
			(layer "F.Fab")
			(hide yes)
			(effects
				(font
					(size 1 1)
					(thickness 0.15)
				)
			)
		)
		(sheetfile "environment-sensor.kicad_sch")
		(attr smd)
		(fp_line
			(start -2.62 2.648)
			(end -2.62 2.249)
			(stroke
				(width 0.15)
				(type solid)
			)
			(layer "F.SilkS")
		)
		(fp_line
			(start -2.221 2.648)
			(end -2.62 2.648)
			(stroke
				(width 0.15)
				(type solid)
			)
			(layer "F.SilkS")
		)
		(fp_line
			(start 2.581 2.648)
			(end 2.178 2.648)
			(stroke
				(width 0.15)
				(type solid)
			)
			(layer "F.SilkS")
		)
		(fp_line
			(start 2.581 2.249)
			(end 2.581 2.648)
			(stroke
				(width 0.15)
				(type solid)
			)
			(layer "F.SilkS")
		)
		(fp_line
			(start -2.221 -2.551)
			(end -2.62 -2.149)
			(stroke
				(width 0.15)
				(type solid)
			)
			(layer "F.SilkS")
		)
		(fp_line
			(start 2.581 -2.551)
			(end 2.581 -2.149)
			(stroke
				(width 0.15)
				(type solid)
			)
			(layer "F.SilkS")
		)
		(fp_line
			(start 2.581 -2.551)
			(end 2.178 -2.551)
			(stroke
				(width 0.15)
				(type solid)
			)
			(layer "F.SilkS")
		)
		(fp_circle
			(center -3.25 -1.702)
			(end -3.2 -1.702)
			(stroke
				(width 0.15)
				(type solid)
			)
			(fill yes)
			(layer "F.SilkS")
		)
		(fp_rect
			(start -1.446 1.474)
			(end -0.246 0.274)
			(stroke
				(width 0.2)
				(type solid)
			)
			(fill yes)
			(layer "F.Paste")
		)
		(fp_rect
			(start 0.203 1.474)
			(end 1.403 0.274)
			(stroke
				(width 0.2)
				(type solid)
			)
			(fill yes)
			(layer "F.Paste")
		)
		(fp_rect
			(start -1.446 -0.175)
			(end -0.246 -1.375)
			(stroke
				(width 0.2)
				(type solid)
			)
			(fill yes)
			(layer "F.Paste")
		)
		(fp_rect
			(start 0.203 -0.175)
			(end 1.403 -1.375)
			(stroke
				(width 0.2)
				(type solid)
			)
			(fill yes)
			(layer "F.Paste")
		)
		(fp_rect
			(start -2.74 -2.75)
			(end 2.75 2.74)
			(stroke
				(width 0.05)
				(type solid)
			)
			(fill no)
			(layer "F.CrtYd")
		)
		(fp_line
			(start -2.499 -2.299)
			(end -2.298 -2.5)
			(stroke
				(width 0.15)
				(type solid)
			)
			(layer "F.Fab")
		)
		(fp_rect
			(start -2.499 -2.5)
			(end 2.5 2.499)
			(stroke
				(width 0.15)
				(type solid)
			)
			(fill no)
			(layer "F.Fab")
		)
		(pad "1" smd rect
			(at -2.495 -1.702 180)
			(size 0.28 0.85)
			(layers "F.Cu" "F.Mask" "F.Paste")
			(net 29 "Net-(U1-3V3OUT)")
			(pinfunction "VCCIO")
			(pintype "power_in")
			(solder_mask_margin 0.07)
		)
		(pad "2" smd rect
			(at -2.495 -1.2 180)
			(size 0.28 0.85)
			(layers "F.Cu" "F.Mask" "F.Paste")
			(net 45 "Net-(U1-RXD)")
			(pinfunction "RXD")
			(pintype "input")
			(solder_mask_margin 0.07)
		)
		(pad "3" smd rect
			(at -2.495 -0.701 180)
			(size 0.28 0.85)
			(layers "F.Cu" "F.Mask" "F.Paste")
			(net 42 "Net-(U1-RI#)")
			(pinfunction "RI#")
			(pintype "input")
			(solder_mask_margin 0.07)
		)
		(pad "4" smd rect
			(at -2.495 -0.201 180)
			(size 0.28 0.85)
			(layers "F.Cu" "F.Mask" "F.Paste")
			(net 1 "GND")
			(pinfunction "GND")
			(pintype "passive")
			(solder_mask_margin 0.07)
		)
		(pad "5" smd rect
			(at -2.495 0.296 180)
			(size 0.28 0.85)
			(layers "F.Cu" "F.Mask" "F.Paste")
			(net 65 "unconnected-(U1-NC-Pad5)")
			(pinfunction "NC")
			(pintype "no_connect")
			(solder_mask_margin 0.07)
		)
		(pad "6" smd rect
			(at -2.495 0.8 180)
			(size 0.28 0.85)
			(layers "F.Cu" "F.Mask" "F.Paste")
			(net 39 "Net-(U1-DSR#)")
			(pinfunction "DSR#")
			(pintype "input")
			(solder_mask_margin 0.07)
		)
		(pad "7" smd rect
			(at -2.495 1.3 180)
			(size 0.28 0.85)
			(layers "F.Cu" "F.Mask" "F.Paste")
			(net 40 "Net-(U1-DCD#)")
			(pinfunction "DCD#")
			(pintype "input")
			(solder_mask_margin 0.07)
		)
		(pad "8" smd rect
			(at -2.495 1.8 180)
			(size 0.28 0.85)
			(layers "F.Cu" "F.Mask" "F.Paste")
			(net 41 "Net-(U1-CTS#)")
			(pinfunction "CTS#")
			(pintype "input")
			(solder_mask_margin 0.07)
		)
		(pad "9" smd rect
			(at -1.768 2.523 180)
			(size 0.85 0.28)
			(layers "F.Cu" "F.Mask" "F.Paste")
			(net 64 "unconnected-(U1-CBUS4-Pad9)")
			(pinfunction "CBUS4")
			(pintype "bidirectional+no_connect")
			(solder_mask_margin 0.07)
		)
		(pad "10" smd rect
			(at -1.269 2.523 180)
			(size 0.85 0.28)
			(layers "F.Cu" "F.Mask" "F.Paste")
			(net 63 "unconnected-(U1-CBUS2-Pad10)")
			(pinfunction "CBUS2")
			(pintype "bidirectional+no_connect")
			(solder_mask_margin 0.07)
		)
		(pad "11" smd rect
			(at -0.772 2.523 180)
			(size 0.85 0.28)
			(layers "F.Cu" "F.Mask" "F.Paste")
			(net 62 "unconnected-(U1-CBUS3-Pad11)")
			(pinfunction "CBUS3")
			(pintype "bidirectional+no_connect")
			(solder_mask_margin 0.07)
		)
		(pad "12" smd rect
			(at -0.272 2.523 180)
			(size 0.85 0.28)
			(layers "F.Cu" "F.Mask" "F.Paste")
			(net 61 "unconnected-(U1-NC-Pad12)")
			(pinfunction "NC")
			(pintype "no_connect")
			(solder_mask_margin 0.07)
		)
		(pad "13" smd rect
			(at 0.229 2.523 180)
			(size 0.85 0.28)
			(layers "F.Cu" "F.Mask" "F.Paste")
			(net 60 "unconnected-(U1-NC-Pad13)")
			(pinfunction "NC")
			(pintype "no_connect")
			(solder_mask_margin 0.07)
		)
		(pad "14" smd rect
			(at 0.728 2.523 180)
			(size 0.85 0.28)
			(layers "F.Cu" "F.Mask" "F.Paste")
			(net 6 "/USB_D_P")
			(pinfunction "USBDP")
			(pintype "bidirectional")
			(solder_mask_margin 0.07)
		)
		(pad "15" smd rect
			(at 1.23 2.523 180)
			(size 0.85 0.28)
			(layers "F.Cu" "F.Mask" "F.Paste")
			(net 7 "/USB_D_N")
			(pinfunction "USBDM")
			(pintype "bidirectional")
			(solder_mask_margin 0.07)
		)
		(pad "16" smd rect
			(at 1.73 2.523 180)
			(size 0.85 0.28)
			(layers "F.Cu" "F.Mask" "F.Paste")
			(net 29 "Net-(U1-3V3OUT)")
			(pinfunction "3V3OUT")
			(pintype "output")
			(solder_mask_margin 0.07)
		)
		(pad "17" smd rect
			(at 2.456 1.8 180)
			(size 0.28 0.85)
			(layers "F.Cu" "F.Mask" "F.Paste")
			(net 1 "GND")
			(pinfunction "GND")
			(pintype "power_in")
			(solder_mask_margin 0.07)
		)
		(pad "18" smd rect
			(at 2.456 1.3 180)
			(size 0.28 0.85)
			(layers "F.Cu" "F.Mask" "F.Paste")
			(net 36 "Net-(U1-RESET#)")
			(pinfunction "RESET#")
			(pintype "input")
			(solder_mask_margin 0.07)
		)
		(pad "19" smd rect
			(at 2.456 0.8 180)
			(size 0.28 0.85)
			(layers "F.Cu" "F.Mask" "F.Paste")
			(net 26 "+5V")
			(pinfunction "VCC")
			(pintype "power_in")
			(solder_mask_margin 0.07)
		)
		(pad "20" smd rect
			(at 2.456 0.296 180)
			(size 0.28 0.85)
			(layers "F.Cu" "F.Mask" "F.Paste")
			(net 1 "GND")
			(pinfunction "GND")
			(pintype "passive")
			(solder_mask_margin 0.07)
		)
		(pad "21" smd rect
			(at 2.456 -0.201 180)
			(size 0.28 0.85)
			(layers "F.Cu" "F.Mask" "F.Paste")
			(net 59 "unconnected-(U1-CBUS1-Pad21)")
			(pinfunction "CBUS1")
			(pintype "bidirectional+no_connect")
			(solder_mask_margin 0.07)
		)
		(pad "22" smd rect
			(at 2.456 -0.701 180)
			(size 0.28 0.85)
			(layers "F.Cu" "F.Mask" "F.Paste")
			(net 43 "Net-(U1-CBUS0)")
			(pinfunction "CBUS0")
			(pintype "bidirectional")
			(solder_mask_margin 0.07)
		)
		(pad "23" smd rect
			(at 2.456 -1.2 180)
			(size 0.28 0.85)
			(layers "F.Cu" "F.Mask" "F.Paste")
			(net 58 "unconnected-(U1-NC-Pad23)")
			(pinfunction "NC")
			(pintype "no_connect")
			(solder_mask_margin 0.07)
		)
		(pad "24" smd rect
			(at 2.456 -1.702 180)
			(size 0.28 0.85)
			(layers "F.Cu" "F.Mask" "F.Paste")
			(net 1 "GND")
			(pinfunction "AGND")
			(pintype "power_in")
			(solder_mask_margin 0.07)
		)
		(pad "25" smd rect
			(at 1.73 -2.426 180)
			(size 0.85 0.28)
			(layers "F.Cu" "F.Mask" "F.Paste")
			(net 57 "unconnected-(U1-NC-Pad25)")
			(pinfunction "NC")
			(pintype "no_connect")
			(solder_mask_margin 0.07)
		)
		(pad "26" smd rect
			(at 1.23 -2.426 180)
			(size 0.85 0.28)
			(layers "F.Cu" "F.Mask" "F.Paste")
			(net 1 "GND")
			(pinfunction "TEST")
			(pintype "input")
			(solder_mask_margin 0.07)
		)
		(pad "27" smd rect
			(at 0.728 -2.426 180)
			(size 0.85 0.28)
			(layers "F.Cu" "F.Mask" "F.Paste")
			(net 56 "unconnected-(U1-OSCI-Pad27)")
			(pinfunction "OSCI")
			(pintype "input+no_connect")
			(solder_mask_margin 0.07)
		)
		(pad "28" smd rect
			(at 0.229 -2.426 180)
			(size 0.85 0.28)
			(layers "F.Cu" "F.Mask" "F.Paste")
			(net 55 "unconnected-(U1-OSCO-Pad28)")
			(pinfunction "OSCO")
			(pintype "output+no_connect")
			(solder_mask_margin 0.07)
		)
		(pad "29" smd rect
			(at -0.272 -2.426 180)
			(size 0.85 0.28)
			(layers "F.Cu" "F.Mask" "F.Paste")
			(net 54 "unconnected-(U1-NC-Pad29)")
			(pinfunction "NC")
			(pintype "no_connect")
			(solder_mask_margin 0.07)
		)
		(pad "30" smd rect
			(at -0.772 -2.426 180)
			(size 0.85 0.28)
			(layers "F.Cu" "F.Mask" "F.Paste")
			(net 44 "Net-(U1-TXD)")
			(pinfunction "TXD")
			(pintype "output")
			(solder_mask_margin 0.07)
		)
		(pad "31" smd rect
			(at -1.269 -2.426 180)
			(size 0.85 0.28)
			(layers "F.Cu" "F.Mask" "F.Paste")
			(net 37 "Net-(U1-DTR#)")
			(pinfunction "DTR#")
			(pintype "output")
			(solder_mask_margin 0.07)
		)
		(pad "32" smd rect
			(at -1.768 -2.426 180)
			(size 0.85 0.28)
			(layers "F.Cu" "F.Mask" "F.Paste")
			(net 38 "Net-(U1-RTS#)")
			(pinfunction "RTS#")
			(pintype "output")
			(solder_mask_margin 0.07)
		)
		(pad "33" smd rect
			(at -0.02 0.048 180)
			(size 3.45 3.45)
			(layers "F.Cu" "F.Mask")
			(net 1 "GND")
			(pinfunction "EP")
			(pintype "passive")
		)
	)
)
